# BASEBOARD_FAB2 (Tioga Pass) — schematic netlist excerpt (pin names and nets, part order shuffled) for the footprints in the layout excerpt that follows; sources: Cadence DE-HDL packaged netlist, KiCad conversion of Wiwynn_Tioga_Pass_MB.brd

R2N31  RES  49.9 1% CHIP  pkg 0402  page 178 : A = SGPIO_PCH_SATA_CLOCK ; B = SGPIO_PCH_SATA_CLOCK_R
C6U7  CAP  10UF 16V 10% X6S  pkg 0805  page 233 : A = VR_FET_SW_P12V_STBY_PVPP_GHJ ; B = GND
C2U15  CAP  0.22UF 16V 10% X7R  pkg 0402  page 107 : A = P3E_CPU0_PE1_PCH_RXP<6> ; B = P3E_CPU0_PE1_SS_RXP<6>

(kicad_pcb
	(version 20260206)
	(generator "pcbnew")
	(generator_version "10.0")
	(general
		(thickness 1.6)
		(legacy_teardrops no)
	)
	(paper "A4")
	(title_block
		(title "Wiwynn_Tioga_Pass_MB.brd")
		(comment 1 "Tioga Pass / footprints 2972-2974 of 4770")
	)
	(layers
		(0 "F.Cu" signal "TOP")
		(4 "In1.Cu" signal "L2GND")
		(6 "In2.Cu" signal "L3")
		(8 "In3.Cu" signal "L4GND")
		(10 "In4.Cu" signal "L5")
		(12 "In5.Cu" signal "L6GND")
		(14 "In6.Cu" signal "L7VCC")
		(16 "In7.Cu" signal "L8VCC")
		(18 "In8.Cu" signal "L9GND")
		(20 "In9.Cu" signal "L10")
		(22 "In10.Cu" signal "L11GND")
		(24 "In11.Cu" signal "L12")
		(26 "In12.Cu" signal "L13GND")
		(2 "B.Cu" signal "BOTTOM")
		(9 "F.Adhes" user "F.Adhesive")
		(11 "B.Adhes" user "B.Adhesive")
		(13 "F.Paste" user "Package Geometry/Pastemask Top")
		(15 "B.Paste" user "Package Geometry/Pastemask Bottom")
		(5 "F.SilkS" user "Ref Des/Silkscreen Top")
		(7 "B.SilkS" user "Ref Des/Silkscreen Bottom")
		(1 "F.Mask" user "Board Geometry/Soldermask Top")
		(3 "B.Mask" user "Board Geometry/Soldermask Bottom")
		(17 "Dwgs.User" user "User.Drawings")
		(19 "Cmts.User" user "User.Comments")
		(21 "Eco1.User" user "User.Eco1")
		(23 "Eco2.User" user "User.Eco2")
		(25 "Edge.Cuts" user "Board Geometry/Outline")
		(27 "Margin" user)
		(31 "F.CrtYd" user "Package Geometry/Place Bound Top")
		(29 "B.CrtYd" user "Package Geometry/Place Bound Bottom")
		(35 "F.Fab" user "Ref Des/Assembly Top")
		(33 "B.Fab" user "Ref Des/Assembly Bottom")
	)
	(footprint ""
		(layer "B.Cu")
		(at 350.110806 -61.257434)
		(property "Reference" "C2U15"
			(at 0 0 0)
			(layer "B.SilkS")
			(hide yes)
			(effects
				(font
					(size 1.27 1.27)
				)
				(justify mirror)
			)
		)
		(property "Value" ""
			(at 0 0 0)
			(layer "B.Fab")
			(effects
				(font
					(size 1.27 1.27)
				)
				(justify mirror)
			)
		)
		(duplicate_pad_numbers_are_jumpers no)
		(fp_poly
			(pts
				(xy -0.3048 -0.1016) (xy -0.3048 0.9906) (xy 0.3048 0.9906) (xy 0.3048 -0.1016)
			)
			(stroke
				(width 0)
				(type default)
			)
			(fill no)
			(layer "B.CrtYd")
		)
		(fp_line
			(start -0.3048 -0.1016)
			(end 0.3048 -0.1016)
			(stroke
				(width 0.1)
				(type default)
			)
			(layer "B.Fab")
		)
		(fp_line
			(start -0.3048 0.9906)
			(end -0.3048 -0.1016)
			(stroke
				(width 0.1)
				(type default)
			)
			(layer "B.Fab")
		)
		(fp_line
			(start 0.3048 -0.1016)
			(end 0.3048 0.9906)
			(stroke
				(width 0.1)
				(type default)
			)
			(layer "B.Fab")
		)
		(fp_line
			(start 0.3048 0.9906)
			(end -0.3048 0.9906)
			(stroke
				(width 0.1)
				(type default)
			)
			(layer "B.Fab")
		)
		(pad "1" smd rect
			(at 0 0 180)
			(size 0.508 0.508)
			(layers "B.Cu" "B.Mask" "B.Paste")
			(net "P3E_CPU0_PE1_PCH_RXP<6>")
		)
		(pad "2" smd rect
			(at 0 0.889 180)
			(size 0.508 0.508)
			(layers "B.Cu" "B.Mask" "B.Paste")
			(net "P3E_CPU0_PE1_SS_RXP<6>")
		)
		(zone
			(layer "B.Cu")
			(hatch none 0.5)
			(connect_pads
				(clearance 0)
			)
			(min_thickness 0.25)
			(keepout
				(tracks allowed)
				(vias not_allowed)
				(pads allowed)
				(copperpour not_allowed)
				(footprints allowed)
			)
			(placement
				(enabled no)
				(sheetname "")
			)
			(fill
				(thermal_gap 0.5)
				(thermal_bridge_width 0.5)
				(island_removal_mode 0)
			)
			(polygon
				(pts
					(xy 350.364806 -61.003434) (xy 349.856806 -61.003434) (xy 349.856806 -60.622434) (xy 350.364806 -60.622434)
				)
			)
		)
		(zone
			(layer "B.Cu")
			(hatch none 0.5)
			(connect_pads
				(clearance 0)
			)
			(min_thickness 0.25)
			(keepout
				(tracks not_allowed)
				(vias allowed)
				(pads allowed)
				(copperpour not_allowed)
				(footprints allowed)
			)
			(placement
				(enabled no)
				(sheetname "")
			)
			(fill
				(thermal_gap 0.5)
				(thermal_bridge_width 0.5)
				(island_removal_mode 0)
			)
			(polygon
				(pts
					(xy 350.364806 -60.622434) (xy 349.856806 -60.622434) (xy 349.856806 -61.003434) (xy 350.364806 -61.003434)
				)
			)
		)
	)
	(footprint ""
		(layer "B.Cu")
		(at 183.16702 -10.91057 90)
		(property "Reference" "C6U7"
			(at -1.47828 0.78994 180)
			(unlocked yes)
			(layer "B.SilkS")
			(effects
				(font
					(size 0.4064 0.254)
					(thickness 0.1524)
				)
				(justify mirror)
			)
		)
		(property "Value" ""
			(at 0 0 90)
			(layer "B.Fab")
			(effects
				(font
					(size 1.27 1.27)
				)
				(justify mirror)
			)
		)
		(duplicate_pad_numbers_are_jumpers no)
		(fp_poly
			(pts
				(xy 0.7239 -0.2159) (xy -0.7239 -0.2159) (xy -0.7239 1.9939) (xy 0.7239 1.9939)
			)
			(stroke
				(width 0)
				(type default)
			)
			(fill no)
			(layer "B.CrtYd")
		)
		(fp_line
			(start 0.7239 -0.2159)
			(end 0.7239 1.9939)
			(stroke
				(width 0.1)
				(type default)
			)
			(layer "B.Fab")
		)
		(fp_line
			(start -0.7239 -0.2159)
			(end 0.7239 -0.2159)
			(stroke
				(width 0.1)
				(type default)
			)
			(layer "B.Fab")
		)
		(fp_line
			(start 0.7239 1.9939)
			(end -0.7239 1.9939)
			(stroke
				(width 0.1)
				(type default)
			)
			(layer "B.Fab")
		)
		(fp_line
			(start -0.7239 1.9939)
			(end -0.7239 -0.2159)
			(stroke
				(width 0.1)
				(type default)
			)
			(layer "B.Fab")
		)
		(pad "1" smd rect
			(at 0 0 270)
			(size 1.27 1.016)
			(layers "B.Cu" "B.Mask" "B.Paste")
			(net "VR_FET_SW_P12V_STBY_PVPP_GHJ")
		)
		(pad "2" smd rect
			(at 0 1.778 270)
			(size 1.27 1.016)
			(layers "B.Cu" "B.Mask" "B.Paste")
			(net "GND")
		)
		(zone
			(layer "B.Cu")
			(hatch none 0.5)
			(connect_pads
				(clearance 0)
			)
			(min_thickness 0.25)
			(keepout
				(tracks not_allowed)
				(vias allowed)
				(pads allowed)
				(copperpour not_allowed)
				(footprints allowed)
			)
			(placement
				(enabled no)
				(sheetname "")
			)
			(fill
				(thermal_gap 0.5)
				(thermal_bridge_width 0.5)
				(island_removal_mode 0)
			)
			(polygon
				(pts
					(xy 183.67502 -11.54557) (xy 183.67502 -10.27557) (xy 184.43702 -10.27557) (xy 184.43702 -11.54557)
				)
			)
		)
	)
	(footprint ""
		(layer "B.Cu")
		(at 389.382 -87.4395)
		(property "Reference" "R2N31"
			(at 0 0 0)
			(layer "B.SilkS")
			(hide yes)
			(effects
				(font
					(size 1.27 1.27)
				)
				(justify mirror)
			)
		)
		(property "Value" ""
			(at 0 0 0)
			(layer "B.Fab")
			(effects
				(font
					(size 1.27 1.27)
				)
				(justify mirror)
			)
		)
		(duplicate_pad_numbers_are_jumpers no)
		(fp_poly
			(pts
				(xy 0.2794 -0.1016) (xy -0.2794 -0.1016) (xy -0.2794 0.9906) (xy 0.2794 0.9906)
			)
			(stroke
				(width 0)
				(type default)
			)
			(fill no)
			(layer "B.CrtYd")
		)
		(fp_line
			(start -0.2794 -0.1016)
			(end 0.2794 -0.1016)
			(stroke
				(width 0.1)
				(type default)
			)
			(layer "B.Fab")
		)
		(fp_line
			(start -0.2794 0.9906)
			(end -0.2794 -0.1016)
			(stroke
				(width 0.1)
				(type default)
			)
			(layer "B.Fab")
		)
		(fp_line
			(start 0.2794 -0.1016)
			(end 0.2794 0.9906)
			(stroke
				(width 0.1)
				(type default)
			)
			(layer "B.Fab")
		)
		(fp_line
			(start 0.2794 0.9906)
			(end -0.2794 0.9906)
			(stroke
				(width 0.1)
				(type default)
			)
			(layer "B.Fab")
		)
		(pad "1" smd rect
			(at 0 0 180)
			(size 0.508 0.508)
			(layers "B.Cu" "B.Mask" "B.Paste")
			(net "SGPIO_PCH_SATA_CLOCK")
		)
		(pad "2" smd rect
			(at 0 0.889 180)
			(size 0.508 0.508)
			(layers "B.Cu" "B.Mask" "B.Paste")
			(net "SGPIO_PCH_SATA_CLOCK_R")
		)
		(zone
			(layer "B.Cu")
			(hatch none 0.5)
			(connect_pads
				(clearance 0)
			)
			(min_thickness 0.25)
			(keepout
				(tracks allowed)
				(vias not_allowed)
				(pads allowed)
				(copperpour not_allowed)
				(footprints allowed)
			)
			(placement
				(enabled no)
				(sheetname "")
			)
			(fill
				(thermal_gap 0.5)
				(thermal_bridge_width 0.5)
				(island_removal_mode 0)
			)
			(polygon
				(pts
					(xy 389.636 -87.1855) (xy 389.128 -87.1855) (xy 389.128 -86.8045) (xy 389.636 -86.8045)
				)
			)
		)
		(zone
			(layer "B.Cu")
			(hatch none 0.5)
			(connect_pads
				(clearance 0)
			)
			(min_thickness 0.25)
			(keepout
				(tracks not_allowed)
				(vias allowed)
				(pads allowed)
				(copperpour not_allowed)
				(footprints allowed)
			)
			(placement
				(enabled no)
				(sheetname "")
			)
			(fill
				(thermal_gap 0.5)
				(thermal_bridge_width 0.5)
				(island_removal_mode 0)
			)
			(polygon
				(pts
					(xy 389.636 -86.8045) (xy 389.128 -86.8045) (xy 389.128 -87.1855) (xy 389.636 -87.1855)
				)
			)
		)
	)
)
